# T6G (Grand Teton) — schematic netlist excerpt (pin names and nets, part order shuffled) for the footprints in the layout excerpt that follows; sources: Cadence DE-HDL packaged netlist, KiCad conversion of 04192023_DAF0TMB3IC0_F0TG_MB_C_brd_V02_OCP.brd

PC205  Q_CAP  560PF 50V 10% EMPTY  pkg C0402  page 219 : A = SW_PVDDCR_CPU1_P1_SW4 ; B = SW_PVDDCR_CPU1_P1_SW4_RC
R6187  Q_RES  10K 1% EMPTY  pkg 0402LF  page 83 : A = FM_SEC_MUX_SEL ; B = GND

(kicad_pcb
	(version 20260206)
	(generator "pcbnew")
	(generator_version "10.0")
	(general
		(thickness 1.6)
		(legacy_teardrops no)
	)
	(paper "A4")
	(title_block
		(title "04192023_DAF0TMB3IC0_F0TG_MB_C_brd_V02_OCP.brd")
		(comment 1 "Grand Teton / footprints 2380-2381 of 8354")
	)
	(layers
		(0 "F.Cu" signal "TOP")
		(4 "In1.Cu" signal "GND")
		(6 "In2.Cu" signal "IN1")
		(8 "In3.Cu" signal "GND1")
		(10 "In4.Cu" signal "IN2")
		(12 "In5.Cu" signal "GND2")
		(14 "In6.Cu" signal "IN3")
		(16 "In7.Cu" signal "GND3")
		(18 "In8.Cu" signal "VCC")
		(20 "In9.Cu" signal "VCC1")
		(22 "In10.Cu" signal "GND4")
		(24 "In11.Cu" signal "IN4")
		(26 "In12.Cu" signal "GND5")
		(28 "In13.Cu" signal "IN5")
		(30 "In14.Cu" signal "GND6")
		(32 "In15.Cu" signal "IN6")
		(34 "In16.Cu" signal "GND7")
		(2 "B.Cu" signal "BOTTOM")
		(9 "F.Adhes" user "F.Adhesive")
		(11 "B.Adhes" user "B.Adhesive")
		(13 "F.Paste" user "Package Geometry/Pastemask Top")
		(15 "B.Paste" user "Package Geometry/Pastemask Bottom")
		(5 "F.SilkS" user "Ref Des/Silkscreen Top")
		(7 "B.SilkS" user "Ref Des/Silkscreen Bottom")
		(1 "F.Mask" user "Board Geometry/Soldermask Top")
		(3 "B.Mask" user "Board Geometry/Soldermask Bottom")
		(17 "Dwgs.User" user "User.Drawings")
		(19 "Cmts.User" user "User.Comments")
		(21 "Eco1.User" user "User.Eco1")
		(23 "Eco2.User" user "User.Eco2")
		(25 "Edge.Cuts" user "Board Geometry/Outline")
		(27 "Margin" user)
		(31 "F.CrtYd" user "Package Geometry/Place Bound Top")
		(29 "B.CrtYd" user "Package Geometry/Place Bound Bottom")
		(35 "F.Fab" user "Ref Des/Assembly Top")
		(33 "B.Fab" user "Ref Des/Assembly Bottom")
	)
	(footprint ""
		(layer "F.Cu")
		(at 169.404792 -101.520498 -90)
		(property "Reference" "R6187"
			(at 0 0 270)
			(layer "F.SilkS")
			(hide yes)
			(effects
				(font
					(size 1.27 1.27)
				)
			)
		)
		(property "Value" ""
			(at 0 0 270)
			(layer "F.Fab")
			(effects
				(font
					(size 1.27 1.27)
				)
			)
		)
		(duplicate_pad_numbers_are_jumpers no)
		(fp_line
			(start -0.7874 0.4064)
			(end -0.7874 -0.4064)
			(stroke
				(width 0.1524)
				(type default)
			)
			(layer "F.SilkS")
		)
		(fp_line
			(start 0.7874 0.4064)
			(end -0.7874 0.4064)
			(stroke
				(width 0.1524)
				(type default)
			)
			(layer "F.SilkS")
		)
		(fp_line
			(start -0.7874 -0.4064)
			(end 0.7874 -0.4064)
			(stroke
				(width 0.1524)
				(type default)
			)
			(layer "F.SilkS")
		)
		(fp_line
			(start 0.7874 -0.4064)
			(end 0.7874 0.4064)
			(stroke
				(width 0.1524)
				(type default)
			)
			(layer "F.SilkS")
		)
		(fp_line
			(start -0.67945 0.3048)
			(end -0.67945 -0.305054)
			(stroke
				(width 0.1)
				(type default)
			)
			(layer "F.Fab")
		)
		(fp_line
			(start -0.12065 0.3048)
			(end -0.67945 0.3048)
			(stroke
				(width 0.1)
				(type default)
			)
			(layer "F.Fab")
		)
		(fp_line
			(start 0.120396 0.3048)
			(end 0.120396 0.2794)
			(stroke
				(width 0.1)
				(type default)
			)
			(layer "F.Fab")
		)
		(fp_line
			(start 0.67945 0.3048)
			(end 0.120396 0.3048)
			(stroke
				(width 0.1)
				(type default)
			)
			(layer "F.Fab")
		)
		(fp_line
			(start -0.12065 0.2794)
			(end -0.12065 0.3048)
			(stroke
				(width 0.1)
				(type default)
			)
			(layer "F.Fab")
		)
		(fp_line
			(start 0.120396 0.2794)
			(end -0.12065 0.2794)
			(stroke
				(width 0.1)
				(type default)
			)
			(layer "F.Fab")
		)
		(fp_line
			(start -0.12065 -0.2794)
			(end 0.12065 -0.2794)
			(stroke
				(width 0.1)
				(type default)
			)
			(layer "F.Fab")
		)
		(fp_line
			(start 0.12065 -0.2794)
			(end 0.12065 -0.3048)
			(stroke
				(width 0.1)
				(type default)
			)
			(layer "F.Fab")
		)
		(fp_line
			(start 0.12065 -0.3048)
			(end 0.67945 -0.3048)
			(stroke
				(width 0.1)
				(type default)
			)
			(layer "F.Fab")
		)
		(fp_line
			(start 0.67945 -0.3048)
			(end 0.67945 0.3048)
			(stroke
				(width 0.1)
				(type default)
			)
			(layer "F.Fab")
		)
		(fp_line
			(start -0.67945 -0.305054)
			(end -0.12065 -0.305054)
			(stroke
				(width 0.1)
				(type default)
			)
			(layer "F.Fab")
		)
		(fp_line
			(start -0.12065 -0.305054)
			(end -0.12065 -0.2794)
			(stroke
				(width 0.1)
				(type default)
			)
			(layer "F.Fab")
		)
		(pad "1" smd circle
			(at -0.40005 0 270)
			(size 0 0)
			(layers "F.Cu" "F.Mask" "F.Paste")
			(net "FM_SEC_MUX_SEL")
		)
		(pad "2" smd circle
			(at 0.40005 0 270)
			(size 0 0)
			(layers "F.Cu" "F.Mask" "F.Paste")
			(net "GND")
		)
	)
	(footprint ""
		(layer "F.Cu")
		(at 58.180732 -343.716864 180)
		(property "Reference" "PC205"
			(at 0 0 180)
			(layer "F.SilkS")
			(hide yes)
			(effects
				(font
					(size 1.27 1.27)
				)
			)
		)
		(property "Value" ""
			(at 0 0 180)
			(layer "F.Fab")
			(effects
				(font
					(size 1.27 1.27)
				)
			)
		)
		(duplicate_pad_numbers_are_jumpers no)
		(fp_line
			(start 0.7874 0.4064)
			(end -0.7874 0.4064)
			(stroke
				(width 0.1524)
				(type default)
			)
			(layer "F.SilkS")
		)
		(fp_line
			(start 0.7874 -0.4064)
			(end 0.7874 0.4064)
			(stroke
				(width 0.1524)
				(type default)
			)
			(layer "F.SilkS")
		)
		(fp_line
			(start -0.7874 0.4064)
			(end -0.7874 -0.4064)
			(stroke
				(width 0.1524)
				(type default)
			)
			(layer "F.SilkS")
		)
		(fp_line
			(start -0.7874 -0.4064)
			(end 0.7874 -0.4064)
			(stroke
				(width 0.1524)
				(type default)
			)
			(layer "F.SilkS")
		)
		(fp_line
			(start 0.67945 0.3048)
			(end 0.120396 0.3048)
			(stroke
				(width 0.1)
				(type default)
			)
			(layer "F.Fab")
		)
		(fp_line
			(start 0.67945 -0.3048)
			(end 0.67945 0.3048)
			(stroke
				(width 0.1)
				(type default)
			)
			(layer "F.Fab")
		)
		(fp_line
			(start 0.12065 -0.2794)
			(end 0.12065 -0.3048)
			(stroke
				(width 0.1)
				(type default)
			)
			(layer "F.Fab")
		)
		(fp_line
			(start 0.12065 -0.3048)
			(end 0.67945 -0.3048)
			(stroke
				(width 0.1)
				(type default)
			)
			(layer "F.Fab")
		)
		(fp_line
			(start 0.120396 0.3048)
			(end 0.120396 0.2794)
			(stroke
				(width 0.1)
				(type default)
			)
			(layer "F.Fab")
		)
		(fp_line
			(start 0.120396 0.2794)
			(end -0.12065 0.2794)
			(stroke
				(width 0.1)
				(type default)
			)
			(layer "F.Fab")
		)
		(fp_line
			(start -0.12065 0.3048)
			(end -0.67945 0.3048)
			(stroke
				(width 0.1)
				(type default)
			)
			(layer "F.Fab")
		)
		(fp_line
			(start -0.12065 0.2794)
			(end -0.12065 0.3048)
			(stroke
				(width 0.1)
				(type default)
			)
			(layer "F.Fab")
		)
		(fp_line
			(start -0.12065 -0.2794)
			(end 0.12065 -0.2794)
			(stroke
				(width 0.1)
				(type default)
			)
			(layer "F.Fab")
		)
		(fp_line
			(start -0.12065 -0.305054)
			(end -0.12065 -0.2794)
			(stroke
				(width 0.1)
				(type default)
			)
			(layer "F.Fab")
		)
		(fp_line
			(start -0.67945 0.3048)
			(end -0.67945 -0.305054)
			(stroke
				(width 0.1)
				(type default)
			)
			(layer "F.Fab")
		)
		(fp_line
			(start -0.67945 -0.305054)
			(end -0.12065 -0.305054)
			(stroke
				(width 0.1)
				(type default)
			)
			(layer "F.Fab")
		)
		(pad "1" smd circle
			(at -0.40005 0 180)
			(size 0 0)
			(layers "F.Cu" "F.Mask" "F.Paste")
			(net "SW_PVDDCR_CPU1_P1_SW4")
		)
		(pad "2" smd circle
			(at 0.40005 0 180)
			(size 0 0)
			(layers "F.Cu" "F.Mask" "F.Paste")
			(net "SW_PVDDCR_CPU1_P1_SW4_RC")
		)
	)
)
